(kicad_pcb
	(version 20260206)
	(generator "pcbnew")
	(generator_version "10.0")
	(general
		(thickness 1.6)
		(legacy_teardrops no)
	)
	(paper "A4")
	(title_block
		(title "01162023_DA0F0TEBIF0_F0T_Expander_BD_F_brd_V02_OCP.brd")
		(comment 1 "Grand Teton / footprints 2447-2453 of 9728")
	)
	(layers
		(0 "F.Cu" signal "TOP")
		(4 "In1.Cu" signal "GND")
		(6 "In2.Cu" signal "VCC")
		(8 "In3.Cu" signal "VCC1")
		(10 "In4.Cu" signal "GND1")
		(12 "In5.Cu" signal "IN1")
		(14 "In6.Cu" signal "GND2")
		(16 "In7.Cu" signal "IN2")
		(18 "In8.Cu" signal "GND3")
		(20 "In9.Cu" signal "IN3")
		(22 "In10.Cu" signal "GND4")
		(24 "In11.Cu" signal "IN4")
		(26 "In12.Cu" signal "GND5")
		(28 "In13.Cu" signal "IN5")
		(30 "In14.Cu" signal "GND6")
		(32 "In15.Cu" signal "IN6")
		(34 "In16.Cu" signal "GND7")
		(2 "B.Cu" signal "BOTTOM")
		(9 "F.Adhes" user "F.Adhesive")
		(11 "B.Adhes" user "B.Adhesive")
		(13 "F.Paste" user "Package Geometry/Pastemask Top")
		(15 "B.Paste" user "Package Geometry/Pastemask Bottom")
		(5 "F.SilkS" user "Ref Des/Silkscreen Top")
		(7 "B.SilkS" user "Ref Des/Silkscreen Bottom")
		(1 "F.Mask" user "Board Geometry/Soldermask Top")
		(3 "B.Mask" user "Board Geometry/Soldermask Bottom")
		(17 "Dwgs.User" user "User.Drawings")
		(19 "Cmts.User" user "User.Comments")
		(21 "Eco1.User" user "User.Eco1")
		(23 "Eco2.User" user "User.Eco2")
		(25 "Edge.Cuts" user "Board Geometry/Outline")
		(27 "Margin" user)
		(31 "F.CrtYd" user "Package Geometry/Place Bound Top")
		(29 "B.CrtYd" user "Package Geometry/Place Bound Bottom")
		(35 "F.Fab" user "Ref Des/Assembly Top")
		(33 "B.Fab" user "Ref Des/Assembly Bottom")
	)
	(footprint ""
		(layer "F.Cu")
		(at 363.459776 -152.71115 -90)
		(property "Reference" "R753"
			(at 0 0 270)
			(layer "F.SilkS")
			(hide yes)
			(effects
				(font
					(size 1.27 1.27)
				)
			)
		)
		(property "Value" ""
			(at 0 0 270)
			(layer "F.Fab")
			(effects
				(font
					(size 1.27 1.27)
				)
			)
		)
		(duplicate_pad_numbers_are_jumpers no)
		(fp_line
			(start -0.7874 0.4064)
			(end -0.7874 -0.4064)
			(stroke
				(width 0.1524)
				(type default)
			)
			(layer "F.SilkS")
		)
		(fp_line
			(start 0.7874 0.4064)
			(end -0.7874 0.4064)
			(stroke
				(width 0.1524)
				(type default)
			)
			(layer "F.SilkS")
		)
		(fp_line
			(start -0.7874 -0.4064)
			(end 0.7874 -0.4064)
			(stroke
				(width 0.1524)
				(type default)
			)
			(layer "F.SilkS")
		)
		(fp_line
			(start 0.7874 -0.4064)
			(end 0.7874 0.4064)
			(stroke
				(width 0.1524)
				(type default)
			)
			(layer "F.SilkS")
		)
		(fp_line
			(start -0.67945 0.3048)
			(end -0.67945 -0.305054)
			(stroke
				(width 0.1)
				(type default)
			)
			(layer "F.Fab")
		)
		(fp_line
			(start -0.12065 0.3048)
			(end -0.67945 0.3048)
			(stroke
				(width 0.1)
				(type default)
			)
			(layer "F.Fab")
		)
		(fp_line
			(start 0.120396 0.3048)
			(end 0.120396 0.2794)
			(stroke
				(width 0.1)
				(type default)
			)
			(layer "F.Fab")
		)
		(fp_line
			(start 0.67945 0.3048)
			(end 0.120396 0.3048)
			(stroke
				(width 0.1)
				(type default)
			)
			(layer "F.Fab")
		)
		(fp_line
			(start -0.12065 0.2794)
			(end -0.12065 0.3048)
			(stroke
				(width 0.1)
				(type default)
			)
			(layer "F.Fab")
		)
		(fp_line
			(start 0.120396 0.2794)
			(end -0.12065 0.2794)
			(stroke
				(width 0.1)
				(type default)
			)
			(layer "F.Fab")
		)
		(fp_line
			(start -0.12065 -0.2794)
			(end 0.12065 -0.2794)
			(stroke
				(width 0.1)
				(type default)
			)
			(layer "F.Fab")
		)
		(fp_line
			(start 0.12065 -0.2794)
			(end 0.12065 -0.3048)
			(stroke
				(width 0.1)
				(type default)
			)
			(layer "F.Fab")
		)
		(fp_line
			(start 0.12065 -0.3048)
			(end 0.67945 -0.3048)
			(stroke
				(width 0.1)
				(type default)
			)
			(layer "F.Fab")
		)
		(fp_line
			(start 0.67945 -0.3048)
			(end 0.67945 0.3048)
			(stroke
				(width 0.1)
				(type default)
			)
			(layer "F.Fab")
		)
		(fp_line
			(start -0.67945 -0.305054)
			(end -0.12065 -0.305054)
			(stroke
				(width 0.1)
				(type default)
			)
			(layer "F.Fab")
		)
		(fp_line
			(start -0.12065 -0.305054)
			(end -0.12065 -0.2794)
			(stroke
				(width 0.1)
				(type default)
			)
			(layer "F.Fab")
		)
		(pad "1" smd circle
			(at -0.40005 0 270)
			(size 0 0)
			(layers "F.Cu" "F.Mask" "F.Paste")
			(net "SMB_BIC_I2C6_MUX_NIC_ADC_R_SCL")
		)
		(pad "2" smd circle
			(at 0.40005 0 270)
			(size 0 0)
			(layers "F.Cu" "F.Mask" "F.Paste")
			(net "SMB_NIC6_ADC_SCL")
		)
	)
	(footprint ""
		(layer "F.Cu")
		(at 27.200352 -256.478786)
		(property "Reference" "C3066"
			(at 0 0 0)
			(layer "F.SilkS")
			(hide yes)
			(effects
				(font
					(size 1.27 1.27)
				)
			)
		)
		(property "Value" ""
			(at 0 0 0)
			(layer "F.Fab")
			(effects
				(font
					(size 1.27 1.27)
				)
			)
		)
		(duplicate_pad_numbers_are_jumpers no)
		(fp_line
			(start -0.299974 -0.150114)
			(end 0.299974 -0.150114)
			(stroke
				(width 0.1)
				(type default)
			)
			(layer "F.Fab")
		)
		(fp_line
			(start -0.299974 0.150114)
			(end -0.299974 -0.150114)
			(stroke
				(width 0.1)
				(type default)
			)
			(layer "F.Fab")
		)
		(fp_line
			(start 0.299974 -0.150114)
			(end 0.299974 0.150114)
			(stroke
				(width 0.1)
				(type default)
			)
			(layer "F.Fab")
		)
		(fp_line
			(start 0.299974 0.150114)
			(end -0.299974 0.150114)
			(stroke
				(width 0.1)
				(type default)
			)
			(layer "F.Fab")
		)
		(pad "1" smd rect
			(at -0.2667 0)
			(size 0.3048 0.381)
			(layers "F.Cu" "F.Mask" "F.Paste")
			(net "P1V8_PLL0_PEX0")
		)
		(pad "2" smd rect
			(at 0.2667 0)
			(size 0.3048 0.381)
			(layers "F.Cu" "F.Mask" "F.Paste")
			(net "GND")
		)
	)
	(footprint ""
		(layer "F.Cu")
		(at 105.361486 -243.976906 -90)
		(property "Reference" "R815"
			(at 0 0 270)
			(layer "F.SilkS")
			(hide yes)
			(effects
				(font
					(size 1.27 1.27)
				)
			)
		)
		(property "Value" ""
			(at 0 0 270)
			(layer "F.Fab")
			(effects
				(font
					(size 1.27 1.27)
				)
			)
		)
		(duplicate_pad_numbers_are_jumpers no)
		(fp_line
			(start -3.937508 1.8796)
			(end 3.937508 1.8796)
			(stroke
				(width 0.1524)
				(type default)
			)
			(layer "F.SilkS")
		)
		(fp_line
			(start 3.937508 1.8796)
			(end 3.937508 -1.8796)
			(stroke
				(width 0.1524)
				(type default)
			)
			(layer "F.SilkS")
		)
		(fp_line
			(start -3.937508 -1.8796)
			(end -3.937508 1.8796)
			(stroke
				(width 0.1524)
				(type default)
			)
			(layer "F.SilkS")
		)
		(fp_line
			(start 3.937508 -1.8796)
			(end -3.937508 -1.8796)
			(stroke
				(width 0.1524)
				(type default)
			)
			(layer "F.SilkS")
		)
		(fp_line
			(start -3.275076 1.674876)
			(end 3.275076 1.674876)
			(stroke
				(width 0.1)
				(type default)
			)
			(layer "F.Fab")
		)
		(fp_line
			(start 3.275076 1.674876)
			(end 3.275076 -1.674876)
			(stroke
				(width 0.1)
				(type default)
			)
			(layer "F.Fab")
		)
		(fp_line
			(start -3.275076 -1.674876)
			(end -3.275076 1.674876)
			(stroke
				(width 0.1)
				(type default)
			)
			(layer "F.Fab")
		)
		(fp_line
			(start 3.275076 -1.674876)
			(end -3.275076 -1.674876)
			(stroke
				(width 0.1)
				(type default)
			)
			(layer "F.Fab")
		)
		(pad "1" smd rect
			(at -2.350008 0 270)
			(size 2.921 3.5052)
			(layers "F.Cu" "F.Mask" "F.Paste")
			(net "P1V8_PEX")
		)
		(pad "2" smd rect
			(at 2.350008 0 270)
			(size 2.921 3.5052)
			(layers "F.Cu" "F.Mask" "F.Paste")
			(net "P1V8_PEX_R")
		)
	)
	(footprint ""
		(layer "F.Cu")
		(at 102.521512 -88.884506)
		(property "Reference" "R1128"
			(at 0 0 0)
			(layer "F.SilkS")
			(hide yes)
			(effects
				(font
					(size 1.27 1.27)
				)
			)
		)
		(property "Value" ""
			(at 0 0 0)
			(layer "F.Fab")
			(effects
				(font
					(size 1.27 1.27)
				)
			)
		)
		(duplicate_pad_numbers_are_jumpers no)
		(fp_line
			(start -1.2954 -0.5842)
			(end 1.2954 -0.5842)
			(stroke
				(width 0.1524)
				(type default)
			)
			(layer "F.SilkS")
		)
		(fp_line
			(start -1.2954 0.5842)
			(end -1.2954 -0.5842)
			(stroke
				(width 0.1524)
				(type default)
			)
			(layer "F.SilkS")
		)
		(fp_line
			(start 1.2954 -0.5842)
			(end 1.2954 0.5842)
			(stroke
				(width 0.1524)
				(type default)
			)
			(layer "F.SilkS")
		)
		(fp_line
			(start 1.2954 0.5842)
			(end -1.2954 0.5842)
			(stroke
				(width 0.1524)
				(type default)
			)
			(layer "F.SilkS")
		)
		(fp_line
			(start -1.1938 -0.406654)
			(end -0.8636 -0.406654)
			(stroke
				(width 0.1)
				(type default)
			)
			(layer "F.Fab")
		)
		(fp_line
			(start -1.1938 0.4064)
			(end -1.1938 -0.406654)
			(stroke
				(width 0.1)
				(type default)
			)
			(layer "F.Fab")
		)
		(fp_line
			(start -0.8636 -0.4572)
			(end 0.8636 -0.4572)
			(stroke
				(width 0.1)
				(type default)
			)
			(layer "F.Fab")
		)
		(fp_line
			(start -0.8636 -0.406654)
			(end -0.8636 -0.4572)
			(stroke
				(width 0.1)
				(type default)
			)
			(layer "F.Fab")
		)
		(fp_line
			(start -0.8636 0.4064)
			(end -1.1938 0.4064)
			(stroke
				(width 0.1)
				(type default)
			)
			(layer "F.Fab")
		)
		(fp_line
			(start -0.8636 0.4318)
			(end -0.8636 0.4064)
			(stroke
				(width 0.1)
				(type default)
			)
			(layer "F.Fab")
		)
		(fp_line
			(start -0.8636 0.4572)
			(end -0.8636 0.4318)
			(stroke
				(width 0.1)
				(type default)
			)
			(layer "F.Fab")
		)
		(fp_line
			(start 0.8636 -0.4572)
			(end 0.8636 -0.406654)
			(stroke
				(width 0.1)
				(type default)
			)
			(layer "F.Fab")
		)
		(fp_line
			(start 0.8636 -0.406654)
			(end 1.1938 -0.406654)
			(stroke
				(width 0.1)
				(type default)
			)
			(layer "F.Fab")
		)
		(fp_line
			(start 0.8636 0.4064)
			(end 0.8636 0.4572)
			(stroke
				(width 0.1)
				(type default)
			)
			(layer "F.Fab")
		)
		(fp_line
			(start 0.8636 0.4572)
			(end -0.8636 0.4572)
			(stroke
				(width 0.1)
				(type default)
			)
			(layer "F.Fab")
		)
		(fp_line
			(start 1.1938 -0.406654)
			(end 1.1938 0.4064)
			(stroke
				(width 0.1)
				(type default)
			)
			(layer "F.Fab")
		)
		(fp_line
			(start 1.1938 0.4064)
			(end 0.8636 0.4064)
			(stroke
				(width 0.1)
				(type default)
			)
			(layer "F.Fab")
		)
		(pad "1" smd rect
			(at -0.7366 0 270)
			(size 0.7112 0.8128)
			(layers "F.Cu" "F.Mask" "F.Paste")
			(net "P3V3_VDD_9ZXL0851_0_7")
		)
		(pad "2" smd rect
			(at 0.7366 0 270)
			(size 0.7112 0.8128)
			(layers "F.Cu" "F.Mask" "F.Paste")
			(net "P3V3_VDDAR_9ZXL0851_0_7")
		)
	)
	(footprint ""
		(layer "F.Cu")
		(at 83.034124 -6.046724)
		(property "Reference" "R5812"
			(at 0 0 0)
			(layer "F.SilkS")
			(hide yes)
			(effects
				(font
					(size 1.27 1.27)
				)
			)
		)
		(property "Value" ""
			(at 0 0 0)
			(layer "F.Fab")
			(effects
				(font
					(size 1.27 1.27)
				)
			)
		)
		(duplicate_pad_numbers_are_jumpers no)
		(fp_line
			(start -0.7874 -0.4064)
			(end 0.7874 -0.4064)
			(stroke
				(width 0.1524)
				(type default)
			)
			(layer "F.SilkS")
		)
		(fp_line
			(start -0.7874 0.4064)
			(end -0.7874 -0.4064)
			(stroke
				(width 0.1524)
				(type default)
			)
			(layer "F.SilkS")
		)
		(fp_line
			(start 0.7874 -0.4064)
			(end 0.7874 0.4064)
			(stroke
				(width 0.1524)
				(type default)
			)
			(layer "F.SilkS")
		)
		(fp_line
			(start 0.7874 0.4064)
			(end -0.7874 0.4064)
			(stroke
				(width 0.1524)
				(type default)
			)
			(layer "F.SilkS")
		)
		(fp_line
			(start -0.67945 -0.305054)
			(end -0.12065 -0.305054)
			(stroke
				(width 0.1)
				(type default)
			)
			(layer "F.Fab")
		)
		(fp_line
			(start -0.67945 0.3048)
			(end -0.67945 -0.305054)
			(stroke
				(width 0.1)
				(type default)
			)
			(layer "F.Fab")
		)
		(fp_line
			(start -0.12065 -0.305054)
			(end -0.12065 -0.2794)
			(stroke
				(width 0.1)
				(type default)
			)
			(layer "F.Fab")
		)
		(fp_line
			(start -0.12065 -0.2794)
			(end 0.12065 -0.2794)
			(stroke
				(width 0.1)
				(type default)
			)
			(layer "F.Fab")
		)
		(fp_line
			(start -0.12065 0.2794)
			(end -0.12065 0.3048)
			(stroke
				(width 0.1)
				(type default)
			)
			(layer "F.Fab")
		)
		(fp_line
			(start -0.12065 0.3048)
			(end -0.67945 0.3048)
			(stroke
				(width 0.1)
				(type default)
			)
			(layer "F.Fab")
		)
		(fp_line
			(start 0.120396 0.2794)
			(end -0.12065 0.2794)
			(stroke
				(width 0.1)
				(type default)
			)
			(layer "F.Fab")
		)
		(fp_line
			(start 0.120396 0.3048)
			(end 0.120396 0.2794)
			(stroke
				(width 0.1)
				(type default)
			)
			(layer "F.Fab")
		)
		(fp_line
			(start 0.12065 -0.3048)
			(end 0.67945 -0.3048)
			(stroke
				(width 0.1)
				(type default)
			)
			(layer "F.Fab")
		)
		(fp_line
			(start 0.12065 -0.2794)
			(end 0.12065 -0.3048)
			(stroke
				(width 0.1)
				(type default)
			)
			(layer "F.Fab")
		)
		(fp_line
			(start 0.67945 -0.3048)
			(end 0.67945 0.3048)
			(stroke
				(width 0.1)
				(type default)
			)
			(layer "F.Fab")
		)
		(fp_line
			(start 0.67945 0.3048)
			(end 0.120396 0.3048)
			(stroke
				(width 0.1)
				(type default)
			)
			(layer "F.Fab")
		)
		(pad "1" smd circle
			(at -0.40005 0)
			(size 0 0)
			(layers "F.Cu" "F.Mask" "F.Paste")
			(net "LM75_2_A1")
		)
		(pad "2" smd circle
			(at 0.40005 0)
			(size 0 0)
			(layers "F.Cu" "F.Mask" "F.Paste")
			(net "GND")
		)
	)
	(footprint ""
		(layer "F.Cu")
		(at 346.71 -205.232 90)
		(property "Reference" "R4148"
			(at 0 0 90)
			(layer "F.SilkS")
			(hide yes)
			(effects
				(font
					(size 1.27 1.27)
				)
			)
		)
		(property "Value" ""
			(at 0 0 90)
			(layer "F.Fab")
			(effects
				(font
					(size 1.27 1.27)
				)
			)
		)
		(duplicate_pad_numbers_are_jumpers no)
		(fp_line
			(start 0.7874 -0.4064)
			(end 0.7874 0.4064)
			(stroke
				(width 0.1524)
				(type default)
			)
			(layer "F.SilkS")
		)
		(fp_line
			(start -0.7874 -0.4064)
			(end 0.7874 -0.4064)
			(stroke
				(width 0.1524)
				(type default)
			)
			(layer "F.SilkS")
		)
		(fp_line
			(start 0.7874 0.4064)
			(end -0.7874 0.4064)
			(stroke
				(width 0.1524)
				(type default)
			)
			(layer "F.SilkS")
		)
		(fp_line
			(start -0.7874 0.4064)
			(end -0.7874 -0.4064)
			(stroke
				(width 0.1524)
				(type default)
			)
			(layer "F.SilkS")
		)
		(fp_line
			(start -0.12065 -0.305054)
			(end -0.12065 -0.2794)
			(stroke
				(width 0.1)
				(type default)
			)
			(layer "F.Fab")
		)
		(fp_line
			(start -0.67945 -0.305054)
			(end -0.12065 -0.305054)
			(stroke
				(width 0.1)
				(type default)
			)
			(layer "F.Fab")
		)
		(fp_line
			(start 0.67945 -0.3048)
			(end 0.67945 0.3048)
			(stroke
				(width 0.1)
				(type default)
			)
			(layer "F.Fab")
		)
		(fp_line
			(start 0.12065 -0.3048)
			(end 0.67945 -0.3048)
			(stroke
				(width 0.1)
				(type default)
			)
			(layer "F.Fab")
		)
		(fp_line
			(start 0.12065 -0.2794)
			(end 0.12065 -0.3048)
			(stroke
				(width 0.1)
				(type default)
			)
			(layer "F.Fab")
		)
		(fp_line
			(start -0.12065 -0.2794)
			(end 0.12065 -0.2794)
			(stroke
				(width 0.1)
				(type default)
			)
			(layer "F.Fab")
		)
		(fp_line
			(start 0.120396 0.2794)
			(end -0.12065 0.2794)
			(stroke
				(width 0.1)
				(type default)
			)
			(layer "F.Fab")
		)
		(fp_line
			(start -0.12065 0.2794)
			(end -0.12065 0.3048)
			(stroke
				(width 0.1)
				(type default)
			)
			(layer "F.Fab")
		)
		(fp_line
			(start 0.67945 0.3048)
			(end 0.120396 0.3048)
			(stroke
				(width 0.1)
				(type default)
			)
			(layer "F.Fab")
		)
		(fp_line
			(start 0.120396 0.3048)
			(end 0.120396 0.2794)
			(stroke
				(width 0.1)
				(type default)
			)
			(layer "F.Fab")
		)
		(fp_line
			(start -0.12065 0.3048)
			(end -0.67945 0.3048)
			(stroke
				(width 0.1)
				(type default)
			)
			(layer "F.Fab")
		)
		(fp_line
			(start -0.67945 0.3048)
			(end -0.67945 -0.305054)
			(stroke
				(width 0.1)
				(type default)
			)
			(layer "F.Fab")
		)
		(pad "1" smd circle
			(at -0.40005 0 90)
			(size 0 0)
			(layers "F.Cu" "F.Mask" "F.Paste")
			(net "PRSNT_SSD1_FPGA_R_N")
		)
		(pad "2" smd circle
			(at 0.40005 0 90)
			(size 0 0)
			(layers "F.Cu" "F.Mask" "F.Paste")
			(net "PRSNT_SSD1_FPGA_N")
		)
	)
	(footprint ""
		(layer "F.Cu")
		(at 211.610448 -210.366102 90)
		(property "Reference" "R5532"
			(at 0 0 90)
			(layer "F.SilkS")
			(hide yes)
			(effects
				(font
					(size 1.27 1.27)
				)
			)
		)
		(property "Value" ""
			(at 0 0 90)
			(layer "F.Fab")
			(effects
				(font
					(size 1.27 1.27)
				)
			)
		)
		(duplicate_pad_numbers_are_jumpers no)
		(fp_line
			(start 0.7874 -0.4064)
			(end 0.7874 0.4064)
			(stroke
				(width 0.1524)
				(type default)
			)
			(layer "F.SilkS")
		)
		(fp_line
			(start -0.7874 -0.4064)
			(end 0.7874 -0.4064)
			(stroke
				(width 0.1524)
				(type default)
			)
			(layer "F.SilkS")
		)
		(fp_line
			(start 0.7874 0.4064)
			(end -0.7874 0.4064)
			(stroke
				(width 0.1524)
				(type default)
			)
			(layer "F.SilkS")
		)
		(fp_line
			(start -0.7874 0.4064)
			(end -0.7874 -0.4064)
			(stroke
				(width 0.1524)
				(type default)
			)
			(layer "F.SilkS")
		)
		(fp_line
			(start -0.12065 -0.305054)
			(end -0.12065 -0.2794)
			(stroke
				(width 0.1)
				(type default)
			)
			(layer "F.Fab")
		)
		(fp_line
			(start -0.67945 -0.305054)
			(end -0.12065 -0.305054)
			(stroke
				(width 0.1)
				(type default)
			)
			(layer "F.Fab")
		)
		(fp_line
			(start 0.67945 -0.3048)
			(end 0.67945 0.3048)
			(stroke
				(width 0.1)
				(type default)
			)
			(layer "F.Fab")
		)
		(fp_line
			(start 0.12065 -0.3048)
			(end 0.67945 -0.3048)
			(stroke
				(width 0.1)
				(type default)
			)
			(layer "F.Fab")
		)
		(fp_line
			(start 0.12065 -0.2794)
			(end 0.12065 -0.3048)
			(stroke
				(width 0.1)
				(type default)
			)
			(layer "F.Fab")
		)
		(fp_line
			(start -0.12065 -0.2794)
			(end 0.12065 -0.2794)
			(stroke
				(width 0.1)
				(type default)
			)
			(layer "F.Fab")
		)
		(fp_line
			(start 0.120396 0.2794)
			(end -0.12065 0.2794)
			(stroke
				(width 0.1)
				(type default)
			)
			(layer "F.Fab")
		)
		(fp_line
			(start -0.12065 0.2794)
			(end -0.12065 0.3048)
			(stroke
				(width 0.1)
				(type default)
			)
			(layer "F.Fab")
		)
		(fp_line
			(start 0.67945 0.3048)
			(end 0.120396 0.3048)
			(stroke
				(width 0.1)
				(type default)
			)
			(layer "F.Fab")
		)
		(fp_line
			(start 0.120396 0.3048)
			(end 0.120396 0.2794)
			(stroke
				(width 0.1)
				(type default)
			)
			(layer "F.Fab")
		)
		(fp_line
			(start -0.12065 0.3048)
			(end -0.67945 0.3048)
			(stroke
				(width 0.1)
				(type default)
			)
			(layer "F.Fab")
		)
		(fp_line
			(start -0.67945 0.3048)
			(end -0.67945 -0.305054)
			(stroke
				(width 0.1)
				(type default)
			)
			(layer "F.Fab")
		)
		(pad "1" smd circle
			(at -0.40005 0 90)
			(size 0 0)
			(layers "F.Cu" "F.Mask" "F.Paste")
			(net "P3V3_AUX")
		)
		(pad "2" smd circle
			(at 0.40005 0 90)
			(size 0 0)
			(layers "F.Cu" "F.Mask" "F.Paste")
			(net "UART_BIC_DEBUG_TX")
		)
	)
)
